# BASEBOARD_FAB2 (Tioga Pass) — schematic netlist excerpt (pin names and nets, part order shuffled) for the footprints in the layout excerpt that follows; sources: Cadence DE-HDL packaged netlist, KiCad conversion of Wiwynn_Tioga_Pass_MB.brd

R9F1  RES  22.1 1.0% CHIP  pkg 0402  page 139 : A = RMII_BMC_PCH_SPRNGVLLE_CRSDV_R ; B = RMII_BMC_PCH_SPRNGVLLE_CRSDV
R7C20  RES  10.0K 1% CHIP  pkg 0402  page 121 : A = CLK_50M_CKMNG_PCH_10GBE ; B = GND
R4D17  RES  27.4 1% CHIP  pkg 0402  page 103 : A = CLK_100M_CPU0_BCLK2_R_DP ; B = CLK_100M_CPU0_BCLK2_DP

(kicad_pcb
	(version 20260206)
	(generator "pcbnew")
	(generator_version "10.0")
	(general
		(thickness 1.6)
		(legacy_teardrops no)
	)
	(paper "A4")
	(title_block
		(title "Wiwynn_Tioga_Pass_MB.brd")
		(comment 1 "Tioga Pass / footprints 426-428 of 4770")
	)
	(layers
		(0 "F.Cu" signal "TOP")
		(4 "In1.Cu" signal "L2GND")
		(6 "In2.Cu" signal "L3")
		(8 "In3.Cu" signal "L4GND")
		(10 "In4.Cu" signal "L5")
		(12 "In5.Cu" signal "L6GND")
		(14 "In6.Cu" signal "L7VCC")
		(16 "In7.Cu" signal "L8VCC")
		(18 "In8.Cu" signal "L9GND")
		(20 "In9.Cu" signal "L10")
		(22 "In10.Cu" signal "L11GND")
		(24 "In11.Cu" signal "L12")
		(26 "In12.Cu" signal "L13GND")
		(2 "B.Cu" signal "BOTTOM")
		(9 "F.Adhes" user "F.Adhesive")
		(11 "B.Adhes" user "B.Adhesive")
		(13 "F.Paste" user "Package Geometry/Pastemask Top")
		(15 "B.Paste" user "Package Geometry/Pastemask Bottom")
		(5 "F.SilkS" user "Ref Des/Silkscreen Top")
		(7 "B.SilkS" user "Ref Des/Silkscreen Bottom")
		(1 "F.Mask" user "Board Geometry/Soldermask Top")
		(3 "B.Mask" user "Board Geometry/Soldermask Bottom")
		(17 "Dwgs.User" user "User.Drawings")
		(19 "Cmts.User" user "User.Comments")
		(21 "Eco1.User" user "User.Eco1")
		(23 "Eco2.User" user "User.Eco2")
		(25 "Edge.Cuts" user "Board Geometry/Outline")
		(27 "Margin" user)
		(31 "F.CrtYd" user "Package Geometry/Place Bound Top")
		(29 "B.CrtYd" user "Package Geometry/Place Bound Bottom")
		(35 "F.Fab" user "Ref Des/Assembly Top")
		(33 "B.Fab" user "Ref Des/Assembly Bottom")
	)
	(footprint ""
		(layer "F.Cu")
		(at 491.0455 -40.0304 90)
		(property "Reference" "R9F1"
			(at 0 0 90)
			(layer "F.SilkS")
			(hide yes)
			(effects
				(font
					(size 1.27 1.27)
				)
			)
		)
		(property "Value" ""
			(at 0 0 90)
			(layer "F.Fab")
			(effects
				(font
					(size 1.27 1.27)
				)
			)
		)
		(duplicate_pad_numbers_are_jumpers no)
		(fp_poly
			(pts
				(xy -0.2794 -0.1016) (xy 0.2794 -0.1016) (xy 0.2794 0.9906) (xy -0.2794 0.9906)
			)
			(stroke
				(width 0)
				(type default)
			)
			(fill no)
			(layer "F.CrtYd")
		)
		(fp_line
			(start 0.2794 -0.1016)
			(end -0.2794 -0.1016)
			(stroke
				(width 0.1)
				(type default)
			)
			(layer "F.Fab")
		)
		(fp_line
			(start -0.2794 -0.1016)
			(end -0.2794 0.9906)
			(stroke
				(width 0.1)
				(type default)
			)
			(layer "F.Fab")
		)
		(fp_line
			(start 0.2794 0.9906)
			(end 0.2794 -0.1016)
			(stroke
				(width 0.1)
				(type default)
			)
			(layer "F.Fab")
		)
		(fp_line
			(start -0.2794 0.9906)
			(end 0.2794 0.9906)
			(stroke
				(width 0.1)
				(type default)
			)
			(layer "F.Fab")
		)
		(pad "1" smd rect
			(at 0 0 90)
			(size 0.508 0.508)
			(layers "F.Cu" "F.Mask" "F.Paste")
			(net "RMII_BMC_PCH_SPRNGVLLE_CRSDV_R")
		)
		(pad "2" smd rect
			(at 0 0.889 90)
			(size 0.508 0.508)
			(layers "F.Cu" "F.Mask" "F.Paste")
			(net "RMII_BMC_PCH_SPRNGVLLE_CRSDV")
		)
		(zone
			(layer "F.Cu")
			(hatch none 0.5)
			(connect_pads
				(clearance 0)
			)
			(min_thickness 0.25)
			(keepout
				(tracks allowed)
				(vias not_allowed)
				(pads allowed)
				(copperpour not_allowed)
				(footprints allowed)
			)
			(placement
				(enabled no)
				(sheetname "")
			)
			(fill
				(thermal_gap 0.5)
				(thermal_bridge_width 0.5)
				(island_removal_mode 0)
			)
			(polygon
				(pts
					(xy 491.2995 -39.7764) (xy 491.2995 -40.2844) (xy 491.6805 -40.2844) (xy 491.6805 -39.7764)
				)
			)
		)
		(zone
			(layer "F.Cu")
			(hatch none 0.5)
			(connect_pads
				(clearance 0)
			)
			(min_thickness 0.25)
			(keepout
				(tracks not_allowed)
				(vias allowed)
				(pads allowed)
				(copperpour not_allowed)
				(footprints allowed)
			)
			(placement
				(enabled no)
				(sheetname "")
			)
			(fill
				(thermal_gap 0.5)
				(thermal_bridge_width 0.5)
				(island_removal_mode 0)
			)
			(polygon
				(pts
					(xy 491.6805 -39.7764) (xy 491.6805 -40.2844) (xy 491.2995 -40.2844) (xy 491.2995 -39.7764)
				)
			)
		)
	)
	(footprint ""
		(layer "F.Cu")
		(at 175.387 -81.407 90)
		(property "Reference" "R4D17"
			(at 0 0 90)
			(layer "F.SilkS")
			(hide yes)
			(effects
				(font
					(size 1.27 1.27)
				)
			)
		)
		(property "Value" ""
			(at 0 0 90)
			(layer "F.Fab")
			(effects
				(font
					(size 1.27 1.27)
				)
			)
		)
		(duplicate_pad_numbers_are_jumpers no)
		(fp_poly
			(pts
				(xy -0.2794 -0.1016) (xy 0.2794 -0.1016) (xy 0.2794 0.9906) (xy -0.2794 0.9906)
			)
			(stroke
				(width 0)
				(type default)
			)
			(fill no)
			(layer "F.CrtYd")
		)
		(fp_line
			(start 0.2794 -0.1016)
			(end -0.2794 -0.1016)
			(stroke
				(width 0.1)
				(type default)
			)
			(layer "F.Fab")
		)
		(fp_line
			(start -0.2794 -0.1016)
			(end -0.2794 0.9906)
			(stroke
				(width 0.1)
				(type default)
			)
			(layer "F.Fab")
		)
		(fp_line
			(start 0.2794 0.9906)
			(end 0.2794 -0.1016)
			(stroke
				(width 0.1)
				(type default)
			)
			(layer "F.Fab")
		)
		(fp_line
			(start -0.2794 0.9906)
			(end 0.2794 0.9906)
			(stroke
				(width 0.1)
				(type default)
			)
			(layer "F.Fab")
		)
		(pad "1" smd rect
			(at 0 0 90)
			(size 0.508 0.508)
			(layers "F.Cu" "F.Mask" "F.Paste")
			(net "CLK_100M_CPU0_BCLK2_R_DP")
		)
		(pad "2" smd rect
			(at 0 0.889 90)
			(size 0.508 0.508)
			(layers "F.Cu" "F.Mask" "F.Paste")
			(net "CLK_100M_CPU0_BCLK2_DP")
		)
		(zone
			(layer "F.Cu")
			(hatch none 0.5)
			(connect_pads
				(clearance 0)
			)
			(min_thickness 0.25)
			(keepout
				(tracks allowed)
				(vias not_allowed)
				(pads allowed)
				(copperpour not_allowed)
				(footprints allowed)
			)
			(placement
				(enabled no)
				(sheetname "")
			)
			(fill
				(thermal_gap 0.5)
				(thermal_bridge_width 0.5)
				(island_removal_mode 0)
			)
			(polygon
				(pts
					(xy 175.641 -81.153) (xy 175.641 -81.661) (xy 176.022 -81.661) (xy 176.022 -81.153)
				)
			)
		)
		(zone
			(layer "F.Cu")
			(hatch none 0.5)
			(connect_pads
				(clearance 0)
			)
			(min_thickness 0.25)
			(keepout
				(tracks not_allowed)
				(vias allowed)
				(pads allowed)
				(copperpour not_allowed)
				(footprints allowed)
			)
			(placement
				(enabled no)
				(sheetname "")
			)
			(fill
				(thermal_gap 0.5)
				(thermal_bridge_width 0.5)
				(island_removal_mode 0)
			)
			(polygon
				(pts
					(xy 176.022 -81.153) (xy 176.022 -81.661) (xy 175.641 -81.661) (xy 175.641 -81.153)
				)
			)
		)
	)
	(footprint ""
		(layer "F.Cu")
		(at 387.604 -88.2015)
		(property "Reference" "R7C20"
			(at 0 0 0)
			(layer "F.SilkS")
			(hide yes)
			(effects
				(font
					(size 1.27 1.27)
				)
			)
		)
		(property "Value" ""
			(at 0 0 0)
			(layer "F.Fab")
			(effects
				(font
					(size 1.27 1.27)
				)
			)
		)
		(duplicate_pad_numbers_are_jumpers no)
		(fp_poly
			(pts
				(xy -0.2794 -0.1016) (xy 0.2794 -0.1016) (xy 0.2794 0.9906) (xy -0.2794 0.9906)
			)
			(stroke
				(width 0)
				(type default)
			)
			(fill no)
			(layer "F.CrtYd")
		)
		(fp_line
			(start -0.2794 -0.1016)
			(end -0.2794 0.9906)
			(stroke
				(width 0.1)
				(type default)
			)
			(layer "F.Fab")
		)
		(fp_line
			(start -0.2794 0.9906)
			(end 0.2794 0.9906)
			(stroke
				(width 0.1)
				(type default)
			)
			(layer "F.Fab")
		)
		(fp_line
			(start 0.2794 -0.1016)
			(end -0.2794 -0.1016)
			(stroke
				(width 0.1)
				(type default)
			)
			(layer "F.Fab")
		)
		(fp_line
			(start 0.2794 0.9906)
			(end 0.2794 -0.1016)
			(stroke
				(width 0.1)
				(type default)
			)
			(layer "F.Fab")
		)
		(pad "1" smd rect
			(at 0 0)
			(size 0.508 0.508)
			(layers "F.Cu" "F.Mask" "F.Paste")
			(net "CLK_50M_CKMNG_PCH_10GBE")
		)
		(pad "2" smd rect
			(at 0 0.889)
			(size 0.508 0.508)
			(layers "F.Cu" "F.Mask" "F.Paste")
			(net "GND")
		)
		(zone
			(layer "F.Cu")
			(hatch none 0.5)
			(connect_pads
				(clearance 0)
			)
			(min_thickness 0.25)
			(keepout
				(tracks allowed)
				(vias not_allowed)
				(pads allowed)
				(copperpour not_allowed)
				(footprints allowed)
			)
			(placement
				(enabled no)
				(sheetname "")
			)
			(fill
				(thermal_gap 0.5)
				(thermal_bridge_width 0.5)
				(island_removal_mode 0)
			)
			(polygon
				(pts
					(xy 387.35 -87.9475) (xy 387.858 -87.9475) (xy 387.858 -87.5665) (xy 387.35 -87.5665)
				)
			)
		)
		(zone
			(layer "F.Cu")
			(hatch none 0.5)
			(connect_pads
				(clearance 0)
			)
			(min_thickness 0.25)
			(keepout
				(tracks not_allowed)
				(vias allowed)
				(pads allowed)
				(copperpour not_allowed)
				(footprints allowed)
			)
			(placement
				(enabled no)
				(sheetname "")
			)
			(fill
				(thermal_gap 0.5)
				(thermal_bridge_width 0.5)
				(island_removal_mode 0)
			)
			(polygon
				(pts
					(xy 387.35 -87.5665) (xy 387.858 -87.5665) (xy 387.858 -87.9475) (xy 387.35 -87.9475)
				)
			)
		)
	)
)
